(kicad_pcb
	(version 20260206)
	(generator "pcbnew")
	(generator_version "10.0")
	(general
		(thickness 1.6)
		(legacy_teardrops no)
	)
	(paper "A4")
	(title_block
		(title "01162023_DA0F0TEBIF0_F0T_Expander_BD_F_brd_V02_OCP.brd")
		(comment 1 "Grand Teton / footprints 72-79 of 9728")
	)
	(layers
		(0 "F.Cu" signal "TOP")
		(4 "In1.Cu" signal "GND")
		(6 "In2.Cu" signal "VCC")
		(8 "In3.Cu" signal "VCC1")
		(10 "In4.Cu" signal "GND1")
		(12 "In5.Cu" signal "IN1")
		(14 "In6.Cu" signal "GND2")
		(16 "In7.Cu" signal "IN2")
		(18 "In8.Cu" signal "GND3")
		(20 "In9.Cu" signal "IN3")
		(22 "In10.Cu" signal "GND4")
		(24 "In11.Cu" signal "IN4")
		(26 "In12.Cu" signal "GND5")
		(28 "In13.Cu" signal "IN5")
		(30 "In14.Cu" signal "GND6")
		(32 "In15.Cu" signal "IN6")
		(34 "In16.Cu" signal "GND7")
		(2 "B.Cu" signal "BOTTOM")
		(9 "F.Adhes" user "F.Adhesive")
		(11 "B.Adhes" user "B.Adhesive")
		(13 "F.Paste" user "Package Geometry/Pastemask Top")
		(15 "B.Paste" user "Package Geometry/Pastemask Bottom")
		(5 "F.SilkS" user "Ref Des/Silkscreen Top")
		(7 "B.SilkS" user "Ref Des/Silkscreen Bottom")
		(1 "F.Mask" user "Board Geometry/Soldermask Top")
		(3 "B.Mask" user "Board Geometry/Soldermask Bottom")
		(17 "Dwgs.User" user "User.Drawings")
		(19 "Cmts.User" user "User.Comments")
		(21 "Eco1.User" user "User.Eco1")
		(23 "Eco2.User" user "User.Eco2")
		(25 "Edge.Cuts" user "Board Geometry/Outline")
		(27 "Margin" user)
		(31 "F.CrtYd" user "Package Geometry/Place Bound Top")
		(29 "B.CrtYd" user "Package Geometry/Place Bound Bottom")
		(35 "F.Fab" user "Ref Des/Assembly Top")
		(33 "B.Fab" user "Ref Des/Assembly Bottom")
	)
	(footprint ""
		(layer "F.Cu")
		(at 264.517632 -115.336574 90)
		(property "Reference" "R247"
			(at 0 0 90)
			(layer "F.SilkS")
			(hide yes)
			(effects
				(font
					(size 1.27 1.27)
				)
			)
		)
		(property "Value" ""
			(at 0 0 90)
			(layer "F.Fab")
			(effects
				(font
					(size 1.27 1.27)
				)
			)
		)
		(duplicate_pad_numbers_are_jumpers no)
		(fp_line
			(start 0.7874 -0.4064)
			(end 0.7874 0.4064)
			(stroke
				(width 0.1524)
				(type default)
			)
			(layer "F.SilkS")
		)
		(fp_line
			(start -0.7874 -0.4064)
			(end 0.7874 -0.4064)
			(stroke
				(width 0.1524)
				(type default)
			)
			(layer "F.SilkS")
		)
		(fp_line
			(start 0.7874 0.4064)
			(end -0.7874 0.4064)
			(stroke
				(width 0.1524)
				(type default)
			)
			(layer "F.SilkS")
		)
		(fp_line
			(start -0.7874 0.4064)
			(end -0.7874 -0.4064)
			(stroke
				(width 0.1524)
				(type default)
			)
			(layer "F.SilkS")
		)
		(fp_line
			(start -0.12065 -0.305054)
			(end -0.12065 -0.2794)
			(stroke
				(width 0.1)
				(type default)
			)
			(layer "F.Fab")
		)
		(fp_line
			(start -0.67945 -0.305054)
			(end -0.12065 -0.305054)
			(stroke
				(width 0.1)
				(type default)
			)
			(layer "F.Fab")
		)
		(fp_line
			(start 0.67945 -0.3048)
			(end 0.67945 0.3048)
			(stroke
				(width 0.1)
				(type default)
			)
			(layer "F.Fab")
		)
		(fp_line
			(start 0.12065 -0.3048)
			(end 0.67945 -0.3048)
			(stroke
				(width 0.1)
				(type default)
			)
			(layer "F.Fab")
		)
		(fp_line
			(start 0.12065 -0.2794)
			(end 0.12065 -0.3048)
			(stroke
				(width 0.1)
				(type default)
			)
			(layer "F.Fab")
		)
		(fp_line
			(start -0.12065 -0.2794)
			(end 0.12065 -0.2794)
			(stroke
				(width 0.1)
				(type default)
			)
			(layer "F.Fab")
		)
		(fp_line
			(start 0.120396 0.2794)
			(end -0.12065 0.2794)
			(stroke
				(width 0.1)
				(type default)
			)
			(layer "F.Fab")
		)
		(fp_line
			(start -0.12065 0.2794)
			(end -0.12065 0.3048)
			(stroke
				(width 0.1)
				(type default)
			)
			(layer "F.Fab")
		)
		(fp_line
			(start 0.67945 0.3048)
			(end 0.120396 0.3048)
			(stroke
				(width 0.1)
				(type default)
			)
			(layer "F.Fab")
		)
		(fp_line
			(start 0.120396 0.3048)
			(end 0.120396 0.2794)
			(stroke
				(width 0.1)
				(type default)
			)
			(layer "F.Fab")
		)
		(fp_line
			(start -0.12065 0.3048)
			(end -0.67945 0.3048)
			(stroke
				(width 0.1)
				(type default)
			)
			(layer "F.Fab")
		)
		(fp_line
			(start -0.67945 0.3048)
			(end -0.67945 -0.305054)
			(stroke
				(width 0.1)
				(type default)
			)
			(layer "F.Fab")
		)
		(pad "1" smd circle
			(at -0.40005 0 90)
			(size 0 0)
			(layers "F.Cu" "F.Mask" "F.Paste")
			(net "PRSNT_NIC4_R_N")
		)
		(pad "2" smd circle
			(at 0.40005 0 90)
			(size 0 0)
			(layers "F.Cu" "F.Mask" "F.Paste")
			(net "PRSNT_NIC4_N")
		)
	)
	(footprint ""
		(layer "F.Cu")
		(at 196.119242 -122.270266 180)
		(property "Reference" "C239"
			(at 0 0 180)
			(layer "F.SilkS")
			(hide yes)
			(effects
				(font
					(size 1.27 1.27)
				)
			)
		)
		(property "Value" ""
			(at 0 0 180)
			(layer "F.Fab")
			(effects
				(font
					(size 1.27 1.27)
				)
			)
		)
		(duplicate_pad_numbers_are_jumpers no)
		(fp_line
			(start 0.299974 0.150114)
			(end -0.299974 0.150114)
			(stroke
				(width 0.1)
				(type default)
			)
			(layer "F.Fab")
		)
		(fp_line
			(start 0.299974 -0.150114)
			(end 0.299974 0.150114)
			(stroke
				(width 0.1)
				(type default)
			)
			(layer "F.Fab")
		)
		(fp_line
			(start -0.299974 0.150114)
			(end -0.299974 -0.150114)
			(stroke
				(width 0.1)
				(type default)
			)
			(layer "F.Fab")
		)
		(fp_line
			(start -0.299974 -0.150114)
			(end 0.299974 -0.150114)
			(stroke
				(width 0.1)
				(type default)
			)
			(layer "F.Fab")
		)
		(pad "1" smd rect
			(at -0.2667 0 180)
			(size 0.3048 0.381)
			(layers "F.Cu" "F.Mask" "F.Paste")
			(net "P5E_PEX1_STN0_TX_DN<2>")
		)
		(pad "2" smd rect
			(at 0.2667 0 180)
			(size 0.3048 0.381)
			(layers "F.Cu" "F.Mask" "F.Paste")
			(net "P5E_PEX1_STN0_TX_C_DN<2>")
		)
	)
	(footprint ""
		(layer "F.Cu")
		(at 244.94871 -162.003994 90)
		(property "Reference" "PR7032"
			(at 0 0 90)
			(layer "F.SilkS")
			(hide yes)
			(effects
				(font
					(size 1.27 1.27)
				)
			)
		)
		(property "Value" ""
			(at 0 0 90)
			(layer "F.Fab")
			(effects
				(font
					(size 1.27 1.27)
				)
			)
		)
		(duplicate_pad_numbers_are_jumpers no)
		(fp_line
			(start 0.7874 -0.4064)
			(end 0.7874 0.4064)
			(stroke
				(width 0.1524)
				(type default)
			)
			(layer "F.SilkS")
		)
		(fp_line
			(start -0.7874 -0.4064)
			(end 0.7874 -0.4064)
			(stroke
				(width 0.1524)
				(type default)
			)
			(layer "F.SilkS")
		)
		(fp_line
			(start 0.7874 0.4064)
			(end -0.7874 0.4064)
			(stroke
				(width 0.1524)
				(type default)
			)
			(layer "F.SilkS")
		)
		(fp_line
			(start -0.7874 0.4064)
			(end -0.7874 -0.4064)
			(stroke
				(width 0.1524)
				(type default)
			)
			(layer "F.SilkS")
		)
		(fp_line
			(start -0.12065 -0.305054)
			(end -0.12065 -0.2794)
			(stroke
				(width 0.1)
				(type default)
			)
			(layer "F.Fab")
		)
		(fp_line
			(start -0.67945 -0.305054)
			(end -0.12065 -0.305054)
			(stroke
				(width 0.1)
				(type default)
			)
			(layer "F.Fab")
		)
		(fp_line
			(start 0.67945 -0.3048)
			(end 0.67945 0.3048)
			(stroke
				(width 0.1)
				(type default)
			)
			(layer "F.Fab")
		)
		(fp_line
			(start 0.12065 -0.3048)
			(end 0.67945 -0.3048)
			(stroke
				(width 0.1)
				(type default)
			)
			(layer "F.Fab")
		)
		(fp_line
			(start 0.12065 -0.2794)
			(end 0.12065 -0.3048)
			(stroke
				(width 0.1)
				(type default)
			)
			(layer "F.Fab")
		)
		(fp_line
			(start -0.12065 -0.2794)
			(end 0.12065 -0.2794)
			(stroke
				(width 0.1)
				(type default)
			)
			(layer "F.Fab")
		)
		(fp_line
			(start 0.120396 0.2794)
			(end -0.12065 0.2794)
			(stroke
				(width 0.1)
				(type default)
			)
			(layer "F.Fab")
		)
		(fp_line
			(start -0.12065 0.2794)
			(end -0.12065 0.3048)
			(stroke
				(width 0.1)
				(type default)
			)
			(layer "F.Fab")
		)
		(fp_line
			(start 0.67945 0.3048)
			(end 0.120396 0.3048)
			(stroke
				(width 0.1)
				(type default)
			)
			(layer "F.Fab")
		)
		(fp_line
			(start 0.120396 0.3048)
			(end 0.120396 0.2794)
			(stroke
				(width 0.1)
				(type default)
			)
			(layer "F.Fab")
		)
		(fp_line
			(start -0.12065 0.3048)
			(end -0.67945 0.3048)
			(stroke
				(width 0.1)
				(type default)
			)
			(layer "F.Fab")
		)
		(fp_line
			(start -0.67945 0.3048)
			(end -0.67945 -0.305054)
			(stroke
				(width 0.1)
				(type default)
			)
			(layer "F.Fab")
		)
		(pad "1" smd circle
			(at -0.40005 0 90)
			(size 0 0)
			(layers "F.Cu" "F.Mask" "F.Paste")
			(net "P12V_NIC4_CO_ISET")
		)
		(pad "2" smd circle
			(at 0.40005 0 90)
			(size 0 0)
			(layers "F.Cu" "F.Mask" "F.Paste")
			(net "GND")
		)
	)
	(footprint ""
		(layer "F.Cu")
		(at 234.040172 -172.55998 -90)
		(property "Reference" "R4256"
			(at 0 0 270)
			(layer "F.SilkS")
			(hide yes)
			(effects
				(font
					(size 1.27 1.27)
				)
			)
		)
		(property "Value" ""
			(at 0 0 270)
			(layer "F.Fab")
			(effects
				(font
					(size 1.27 1.27)
				)
			)
		)
		(duplicate_pad_numbers_are_jumpers no)
		(fp_line
			(start -0.7874 0.4064)
			(end -0.7874 -0.4064)
			(stroke
				(width 0.1524)
				(type default)
			)
			(layer "F.SilkS")
		)
		(fp_line
			(start 0.7874 0.4064)
			(end -0.7874 0.4064)
			(stroke
				(width 0.1524)
				(type default)
			)
			(layer "F.SilkS")
		)
		(fp_line
			(start -0.7874 -0.4064)
			(end 0.7874 -0.4064)
			(stroke
				(width 0.1524)
				(type default)
			)
			(layer "F.SilkS")
		)
		(fp_line
			(start 0.7874 -0.4064)
			(end 0.7874 0.4064)
			(stroke
				(width 0.1524)
				(type default)
			)
			(layer "F.SilkS")
		)
		(fp_line
			(start -0.67945 0.3048)
			(end -0.67945 -0.305054)
			(stroke
				(width 0.1)
				(type default)
			)
			(layer "F.Fab")
		)
		(fp_line
			(start -0.12065 0.3048)
			(end -0.67945 0.3048)
			(stroke
				(width 0.1)
				(type default)
			)
			(layer "F.Fab")
		)
		(fp_line
			(start 0.120396 0.3048)
			(end 0.120396 0.2794)
			(stroke
				(width 0.1)
				(type default)
			)
			(layer "F.Fab")
		)
		(fp_line
			(start 0.67945 0.3048)
			(end 0.120396 0.3048)
			(stroke
				(width 0.1)
				(type default)
			)
			(layer "F.Fab")
		)
		(fp_line
			(start -0.12065 0.2794)
			(end -0.12065 0.3048)
			(stroke
				(width 0.1)
				(type default)
			)
			(layer "F.Fab")
		)
		(fp_line
			(start 0.120396 0.2794)
			(end -0.12065 0.2794)
			(stroke
				(width 0.1)
				(type default)
			)
			(layer "F.Fab")
		)
		(fp_line
			(start -0.12065 -0.2794)
			(end 0.12065 -0.2794)
			(stroke
				(width 0.1)
				(type default)
			)
			(layer "F.Fab")
		)
		(fp_line
			(start 0.12065 -0.2794)
			(end 0.12065 -0.3048)
			(stroke
				(width 0.1)
				(type default)
			)
			(layer "F.Fab")
		)
		(fp_line
			(start 0.12065 -0.3048)
			(end 0.67945 -0.3048)
			(stroke
				(width 0.1)
				(type default)
			)
			(layer "F.Fab")
		)
		(fp_line
			(start 0.67945 -0.3048)
			(end 0.67945 0.3048)
			(stroke
				(width 0.1)
				(type default)
			)
			(layer "F.Fab")
		)
		(fp_line
			(start -0.67945 -0.305054)
			(end -0.12065 -0.305054)
			(stroke
				(width 0.1)
				(type default)
			)
			(layer "F.Fab")
		)
		(fp_line
			(start -0.12065 -0.305054)
			(end -0.12065 -0.2794)
			(stroke
				(width 0.1)
				(type default)
			)
			(layer "F.Fab")
		)
		(pad "1" smd circle
			(at -0.40005 0 270)
			(size 0 0)
			(layers "F.Cu" "F.Mask" "F.Paste")
			(net "RST_BIC_SRST_N")
		)
		(pad "2" smd circle
			(at 0.40005 0 270)
			(size 0 0)
			(layers "F.Cu" "F.Mask" "F.Paste")
			(net "RST_BIC_SRST_R_N")
		)
	)
	(footprint ""
		(layer "F.Cu")
		(at 291.97173 -24.807418)
		(property "Reference" "R441"
			(at 0 0 0)
			(layer "F.SilkS")
			(hide yes)
			(effects
				(font
					(size 1.27 1.27)
				)
			)
		)
		(property "Value" ""
			(at 0 0 0)
			(layer "F.Fab")
			(effects
				(font
					(size 1.27 1.27)
				)
			)
		)
		(duplicate_pad_numbers_are_jumpers no)
		(fp_line
			(start -0.7874 -0.4064)
			(end 0.7874 -0.4064)
			(stroke
				(width 0.1524)
				(type default)
			)
			(layer "F.SilkS")
		)
		(fp_line
			(start -0.7874 0.4064)
			(end -0.7874 -0.4064)
			(stroke
				(width 0.1524)
				(type default)
			)
			(layer "F.SilkS")
		)
		(fp_line
			(start 0.7874 -0.4064)
			(end 0.7874 0.4064)
			(stroke
				(width 0.1524)
				(type default)
			)
			(layer "F.SilkS")
		)
		(fp_line
			(start 0.7874 0.4064)
			(end -0.7874 0.4064)
			(stroke
				(width 0.1524)
				(type default)
			)
			(layer "F.SilkS")
		)
		(fp_line
			(start -0.67945 -0.305054)
			(end -0.12065 -0.305054)
			(stroke
				(width 0.1)
				(type default)
			)
			(layer "F.Fab")
		)
		(fp_line
			(start -0.67945 0.3048)
			(end -0.67945 -0.305054)
			(stroke
				(width 0.1)
				(type default)
			)
			(layer "F.Fab")
		)
		(fp_line
			(start -0.12065 -0.305054)
			(end -0.12065 -0.2794)
			(stroke
				(width 0.1)
				(type default)
			)
			(layer "F.Fab")
		)
		(fp_line
			(start -0.12065 -0.2794)
			(end 0.12065 -0.2794)
			(stroke
				(width 0.1)
				(type default)
			)
			(layer "F.Fab")
		)
		(fp_line
			(start -0.12065 0.2794)
			(end -0.12065 0.3048)
			(stroke
				(width 0.1)
				(type default)
			)
			(layer "F.Fab")
		)
		(fp_line
			(start -0.12065 0.3048)
			(end -0.67945 0.3048)
			(stroke
				(width 0.1)
				(type default)
			)
			(layer "F.Fab")
		)
		(fp_line
			(start 0.120396 0.2794)
			(end -0.12065 0.2794)
			(stroke
				(width 0.1)
				(type default)
			)
			(layer "F.Fab")
		)
		(fp_line
			(start 0.120396 0.3048)
			(end 0.120396 0.2794)
			(stroke
				(width 0.1)
				(type default)
			)
			(layer "F.Fab")
		)
		(fp_line
			(start 0.12065 -0.3048)
			(end 0.67945 -0.3048)
			(stroke
				(width 0.1)
				(type default)
			)
			(layer "F.Fab")
		)
		(fp_line
			(start 0.12065 -0.2794)
			(end 0.12065 -0.3048)
			(stroke
				(width 0.1)
				(type default)
			)
			(layer "F.Fab")
		)
		(fp_line
			(start 0.67945 -0.3048)
			(end 0.67945 0.3048)
			(stroke
				(width 0.1)
				(type default)
			)
			(layer "F.Fab")
		)
		(fp_line
			(start 0.67945 0.3048)
			(end 0.120396 0.3048)
			(stroke
				(width 0.1)
				(type default)
			)
			(layer "F.Fab")
		)
		(pad "1" smd circle
			(at -0.40005 0)
			(size 0 0)
			(layers "F.Cu" "F.Mask" "F.Paste")
			(net "P3V3_SSD10")
		)
		(pad "2" smd circle
			(at 0.40005 0)
			(size 0 0)
			(layers "F.Cu" "F.Mask" "F.Paste")
			(net "PU_CLKREQ10")
		)
	)
	(footprint ""
		(layer "F.Cu")
		(at 198.913496 -114.42954 180)
		(property "Reference" "R187"
			(at 0 0 180)
			(layer "F.SilkS")
			(hide yes)
			(effects
				(font
					(size 1.27 1.27)
				)
			)
		)
		(property "Value" ""
			(at 0 0 180)
			(layer "F.Fab")
			(effects
				(font
					(size 1.27 1.27)
				)
			)
		)
		(duplicate_pad_numbers_are_jumpers no)
		(fp_line
			(start 0.7874 0.4064)
			(end -0.7874 0.4064)
			(stroke
				(width 0.1524)
				(type default)
			)
			(layer "F.SilkS")
		)
		(fp_line
			(start 0.7874 -0.4064)
			(end 0.7874 0.4064)
			(stroke
				(width 0.1524)
				(type default)
			)
			(layer "F.SilkS")
		)
		(fp_line
			(start -0.7874 0.4064)
			(end -0.7874 -0.4064)
			(stroke
				(width 0.1524)
				(type default)
			)
			(layer "F.SilkS")
		)
		(fp_line
			(start -0.7874 -0.4064)
			(end 0.7874 -0.4064)
			(stroke
				(width 0.1524)
				(type default)
			)
			(layer "F.SilkS")
		)
		(fp_line
			(start 0.67945 0.3048)
			(end 0.120396 0.3048)
			(stroke
				(width 0.1)
				(type default)
			)
			(layer "F.Fab")
		)
		(fp_line
			(start 0.67945 -0.3048)
			(end 0.67945 0.3048)
			(stroke
				(width 0.1)
				(type default)
			)
			(layer "F.Fab")
		)
		(fp_line
			(start 0.12065 -0.2794)
			(end 0.12065 -0.3048)
			(stroke
				(width 0.1)
				(type default)
			)
			(layer "F.Fab")
		)
		(fp_line
			(start 0.12065 -0.3048)
			(end 0.67945 -0.3048)
			(stroke
				(width 0.1)
				(type default)
			)
			(layer "F.Fab")
		)
		(fp_line
			(start 0.120396 0.3048)
			(end 0.120396 0.2794)
			(stroke
				(width 0.1)
				(type default)
			)
			(layer "F.Fab")
		)
		(fp_line
			(start 0.120396 0.2794)
			(end -0.12065 0.2794)
			(stroke
				(width 0.1)
				(type default)
			)
			(layer "F.Fab")
		)
		(fp_line
			(start -0.12065 0.3048)
			(end -0.67945 0.3048)
			(stroke
				(width 0.1)
				(type default)
			)
			(layer "F.Fab")
		)
		(fp_line
			(start -0.12065 0.2794)
			(end -0.12065 0.3048)
			(stroke
				(width 0.1)
				(type default)
			)
			(layer "F.Fab")
		)
		(fp_line
			(start -0.12065 -0.2794)
			(end 0.12065 -0.2794)
			(stroke
				(width 0.1)
				(type default)
			)
			(layer "F.Fab")
		)
		(fp_line
			(start -0.12065 -0.305054)
			(end -0.12065 -0.2794)
			(stroke
				(width 0.1)
				(type default)
			)
			(layer "F.Fab")
		)
		(fp_line
			(start -0.67945 0.3048)
			(end -0.67945 -0.305054)
			(stroke
				(width 0.1)
				(type default)
			)
			(layer "F.Fab")
		)
		(fp_line
			(start -0.67945 -0.305054)
			(end -0.12065 -0.305054)
			(stroke
				(width 0.1)
				(type default)
			)
			(layer "F.Fab")
		)
		(pad "1" smd circle
			(at -0.40005 0 180)
			(size 0 0)
			(layers "F.Cu" "F.Mask" "F.Paste")
			(net "NIC3_BIF2_N")
		)
		(pad "2" smd circle
			(at 0.40005 0 180)
			(size 0 0)
			(layers "F.Cu" "F.Mask" "F.Paste")
			(net "GND")
		)
	)
	(footprint ""
		(layer "F.Cu")
		(at 298.961302 -356.244906 90)
		(property "Reference" "C2371"
			(at 0 0 90)
			(layer "F.SilkS")
			(hide yes)
			(effects
				(font
					(size 1.27 1.27)
				)
			)
		)
		(property "Value" ""
			(at 0 0 90)
			(layer "F.Fab")
			(effects
				(font
					(size 1.27 1.27)
				)
			)
		)
		(duplicate_pad_numbers_are_jumpers no)
		(fp_line
			(start 0.299974 -0.150114)
			(end 0.299974 0.150114)
			(stroke
				(width 0.1)
				(type default)
			)
			(layer "F.Fab")
		)
		(fp_line
			(start -0.299974 -0.150114)
			(end 0.299974 -0.150114)
			(stroke
				(width 0.1)
				(type default)
			)
			(layer "F.Fab")
		)
		(fp_line
			(start 0.299974 0.150114)
			(end -0.299974 0.150114)
			(stroke
				(width 0.1)
				(type default)
			)
			(layer "F.Fab")
		)
		(fp_line
			(start -0.299974 0.150114)
			(end -0.299974 -0.150114)
			(stroke
				(width 0.1)
				(type default)
			)
			(layer "F.Fab")
		)
		(pad "1" smd rect
			(at -0.2667 0 90)
			(size 0.3048 0.381)
			(layers "F.Cu" "F.Mask" "F.Paste")
			(net "P5E_PEX2_STN4_TX_DP<64>")
		)
		(pad "2" smd rect
			(at 0.2667 0 90)
			(size 0.3048 0.381)
			(layers "F.Cu" "F.Mask" "F.Paste")
			(net "P5E_PEX2_STN4_TX_C_DP<64>")
		)
	)
	(footprint ""
		(layer "F.Cu")
		(at 374.27154 -356.244906 90)
		(property "Reference" "C782"
			(at 0 0 90)
			(layer "F.SilkS")
			(hide yes)
			(effects
				(font
					(size 1.27 1.27)
				)
			)
		)
		(property "Value" ""
			(at 0 0 90)
			(layer "F.Fab")
			(effects
				(font
					(size 1.27 1.27)
				)
			)
		)
		(duplicate_pad_numbers_are_jumpers no)
		(fp_line
			(start 0.299974 -0.150114)
			(end 0.299974 0.150114)
			(stroke
				(width 0.1)
				(type default)
			)
			(layer "F.Fab")
		)
		(fp_line
			(start -0.299974 -0.150114)
			(end 0.299974 -0.150114)
			(stroke
				(width 0.1)
				(type default)
			)
			(layer "F.Fab")
		)
		(fp_line
			(start 0.299974 0.150114)
			(end -0.299974 0.150114)
			(stroke
				(width 0.1)
				(type default)
			)
			(layer "F.Fab")
		)
		(fp_line
			(start -0.299974 0.150114)
			(end -0.299974 -0.150114)
			(stroke
				(width 0.1)
				(type default)
			)
			(layer "F.Fab")
		)
		(pad "1" smd rect
			(at -0.2667 0 90)
			(size 0.3048 0.381)
			(layers "F.Cu" "F.Mask" "F.Paste")
			(net "P5E_PEX3_STN6_TX_DP<101>")
		)
		(pad "2" smd rect
			(at 0.2667 0 90)
			(size 0.3048 0.381)
			(layers "F.Cu" "F.Mask" "F.Paste")
			(net "P5E_PEX3_STN6_TX_C_DP<101>")
		)
	)
)
